(kicad_pcb
	(version 20260206)
	(generator "pcbnew")
	(generator_version "10.0")
	(general
		(thickness 1.6)
		(legacy_teardrops no)
	)
	(paper "A4")
	(title_block
		(title "Bryce Canyon_SCC_16316-1_OCP.brd")
		(comment 1 "Bryce Canyon / footprints 220-226 of 1561")
	)
	(layers
		(0 "F.Cu" signal "TOP")
		(4 "In1.Cu" signal "L2GND")
		(6 "In2.Cu" signal "L3")
		(8 "In3.Cu" signal "L4VCC")
		(10 "In4.Cu" signal "L5VCC")
		(12 "In5.Cu" signal "L6")
		(14 "In6.Cu" signal "L7GND")
		(2 "B.Cu" signal "BOTTOM")
		(9 "F.Adhes" user "F.Adhesive")
		(11 "B.Adhes" user "B.Adhesive")
		(13 "F.Paste" user "Package Geometry/Pastemask Top")
		(15 "B.Paste" user "Package Geometry/Pastemask Bottom")
		(5 "F.SilkS" user "Ref Des/Silkscreen Top")
		(7 "B.SilkS" user "Ref Des/Silkscreen Bottom")
		(1 "F.Mask" user "Board Geometry/Soldermask Top")
		(3 "B.Mask" user "Board Geometry/Soldermask Bottom")
		(17 "Dwgs.User" user "User.Drawings")
		(19 "Cmts.User" user "User.Comments")
		(21 "Eco1.User" user "User.Eco1")
		(23 "Eco2.User" user "User.Eco2")
		(25 "Edge.Cuts" user "Board Geometry/Outline")
		(27 "Margin" user)
		(31 "F.CrtYd" user "Package Geometry/Place Bound Top")
		(29 "B.CrtYd" user "Package Geometry/Place Bound Bottom")
		(35 "F.Fab" user "Ref Des/Assembly Top")
		(33 "B.Fab" user "Ref Des/Assembly Bottom")
	)
	(footprint ""
		(layer "F.Cu")
		(at 175.7934 -76.7334 90)
		(property "Reference" "C385"
			(at 0 0 90)
			(layer "F.SilkS")
			(hide yes)
			(effects
				(font
					(size 1.27 1.27)
				)
			)
		)
		(property "Value" "SC1U16V2KX-7-GP"
			(at 1.7526 -1.6002 90)
			(unlocked yes)
			(layer "F.Fab")
			(hide yes)
			(effects
				(font
					(size 1.016 1.016)
					(thickness 0.1524)
				)
			)
		)
		(property "Device Type" "C402-TO0D2H24"
			(at 1.7526 -3.1242 90)
			(unlocked yes)
			(layer "F.Fab")
			(hide yes)
			(effects
				(font
					(size 1.016 1.016)
					(thickness 0.1524)
				)
			)
		)
		(duplicate_pad_numbers_are_jumpers no)
		(fp_rect
			(start -0.4826 0.889)
			(end 0.4826 -0.889)
			(stroke
				(width 0)
				(type default)
			)
			(fill no)
			(layer "F.CrtYd")
		)
		(fp_rect
			(start -0.4826 0.889)
			(end 0.4826 -0.889)
			(stroke
				(width 0)
				(type default)
			)
			(fill no)
			(layer "F.Fab")
		)
		(pad "1" smd custom
			(at 0 -0.4572 90)
			(size 0.1524 0.1524)
			(layers "F.Cu" "F.Mask" "F.Paste")
			(net "PCE_AVDD")
			(options
				(clearance outline)
				(anchor circle)
			)
			(primitives
				(gr_poly
					(pts
						(arc
							(start -0.254 0.3048)
							(mid -0.325842 0.275042)
							(end -0.3556 0.2032)
						)
						(arc
							(start -0.3556 -0.2032)
							(mid -0.325842 -0.275042)
							(end -0.254 -0.3048)
						)
						(arc
							(start 0.254 -0.3048)
							(mid 0.325842 -0.275042)
							(end 0.3556 -0.2032)
						)
						(arc
							(start 0.3556 0.2032)
							(mid 0.325842 0.275042)
							(end 0.254 0.3048)
						)
					)
					(width 0)
					(fill yes)
				)
			)
		)
		(pad "2" smd custom
			(at 0 0.4572 90)
			(size 0.1524 0.1524)
			(layers "F.Cu" "F.Mask" "F.Paste")
			(net "GND")
			(options
				(clearance outline)
				(anchor circle)
			)
			(primitives
				(gr_poly
					(pts
						(arc
							(start -0.254 0.3048)
							(mid -0.325842 0.275042)
							(end -0.3556 0.2032)
						)
						(arc
							(start -0.3556 -0.2032)
							(mid -0.325842 -0.275042)
							(end -0.254 -0.3048)
						)
						(arc
							(start 0.254 -0.3048)
							(mid 0.325842 -0.275042)
							(end 0.3556 -0.2032)
						)
						(arc
							(start 0.3556 0.2032)
							(mid 0.325842 0.275042)
							(end 0.254 0.3048)
						)
					)
					(width 0)
					(fill yes)
				)
			)
		)
	)
	(footprint ""
		(layer "F.Cu")
		(at 21.7932 -50.6476 90)
		(property "Reference" "C652"
			(at 0 0 90)
			(layer "F.SilkS")
			(hide yes)
			(effects
				(font
					(size 1.27 1.27)
				)
			)
		)
		(property "Value" "SCD1U50V3KX-GP"
			(at 0 -2.8194 90)
			(unlocked yes)
			(layer "F.Fab")
			(hide yes)
			(effects
				(font
					(size 1.016 1.016)
					(thickness 0.1524)
				)
			)
		)
		(property "Device Type" "C603H36"
			(at 0 -4.3434 90)
			(unlocked yes)
			(layer "F.Fab")
			(hide yes)
			(effects
				(font
					(size 1.016 1.016)
					(thickness 0.1524)
				)
			)
		)
		(duplicate_pad_numbers_are_jumpers no)
		(fp_line
			(start 0.508 0)
			(end -0.508 0)
			(stroke
				(width 0.2032)
				(type default)
			)
			(layer "F.SilkS")
		)
		(fp_rect
			(start -0.5842 1.3335)
			(end 0.5842 -1.3335)
			(stroke
				(width 0)
				(type default)
			)
			(fill no)
			(layer "F.CrtYd")
		)
		(fp_rect
			(start -0.5842 1.3335)
			(end 0.5842 -1.3335)
			(stroke
				(width 0)
				(type default)
			)
			(fill no)
			(layer "F.Fab")
		)
		(pad "1" smd custom
			(at 0 -0.762 90)
			(size 0.2159 0.2159)
			(layers "F.Cu" "F.Mask" "F.Paste")
			(net "MB0_PSET_R")
			(options
				(clearance outline)
				(anchor circle)
			)
			(primitives
				(gr_poly
					(pts
						(arc
							(start -0.3302 -0.4318)
							(mid -0.402042 -0.402042)
							(end -0.4318 -0.3302)
						)
						(arc
							(start -0.4318 0.3302)
							(mid -0.402042 0.402042)
							(end -0.3302 0.4318)
						)
						(arc
							(start 0.3302 0.4318)
							(mid 0.402042 0.402042)
							(end 0.4318 0.3302)
						)
						(arc
							(start 0.4318 -0.3302)
							(mid 0.402042 -0.402042)
							(end 0.3302 -0.4318)
						)
					)
					(width 0)
					(fill yes)
				)
			)
		)
		(pad "2" smd custom
			(at 0 0.762 90)
			(size 0.2159 0.2159)
			(layers "F.Cu" "F.Mask" "F.Paste")
			(net "AGND_CURRENT_MON")
			(options
				(clearance outline)
				(anchor circle)
			)
			(primitives
				(gr_poly
					(pts
						(arc
							(start -0.3302 -0.4318)
							(mid -0.402042 -0.402042)
							(end -0.4318 -0.3302)
						)
						(arc
							(start -0.4318 0.3302)
							(mid -0.402042 0.402042)
							(end -0.3302 0.4318)
						)
						(arc
							(start 0.3302 0.4318)
							(mid 0.402042 0.402042)
							(end 0.4318 0.3302)
						)
						(arc
							(start 0.4318 -0.3302)
							(mid 0.402042 -0.402042)
							(end 0.3302 -0.4318)
						)
					)
					(width 0)
					(fill yes)
				)
			)
		)
	)
	(footprint ""
		(layer "F.Cu")
		(at 22.1742 -48.4886 90)
		(property "Reference" "R22"
			(at 0 0 90)
			(layer "F.SilkS")
			(hide yes)
			(effects
				(font
					(size 1.27 1.27)
				)
			)
		)
		(property "Value" "226KR2F-GP"
			(at 0.064008 -3.993896 90)
			(unlocked yes)
			(layer "F.Fab")
			(hide yes)
			(effects
				(font
					(size 1.016 1.016)
					(thickness 0.1524)
				)
			)
		)
		(property "Device Type" "R402H16"
			(at 0.064008 -5.517896 90)
			(unlocked yes)
			(layer "F.Fab")
			(hide yes)
			(effects
				(font
					(size 1.016 1.016)
					(thickness 0.1524)
				)
			)
		)
		(duplicate_pad_numbers_are_jumpers no)
		(fp_line
			(start 0.508 -0.9398)
			(end -0.508 -0.9398)
			(stroke
				(width 0.1524)
				(type default)
			)
			(layer "F.SilkS")
		)
		(fp_line
			(start -0.508 -0.9398)
			(end -0.508 0.9398)
			(stroke
				(width 0.1524)
				(type default)
			)
			(layer "F.SilkS")
		)
		(fp_rect
			(start -0.508 0.9398)
			(end 0.508 -0.9398)
			(stroke
				(width 0)
				(type default)
			)
			(fill no)
			(layer "F.CrtYd")
		)
		(fp_rect
			(start -0.508 0.9398)
			(end 0.508 -0.9398)
			(stroke
				(width 0)
				(type default)
			)
			(fill no)
			(layer "F.Fab")
		)
		(pad "1" smd custom
			(at 0 -0.4445 90)
			(size 0.1397 0.1397)
			(layers "F.Cu" "F.Mask" "F.Paste")
			(net "MB0_PSET_R")
			(options
				(clearance outline)
				(anchor circle)
			)
			(primitives
				(gr_poly
					(pts
						(arc
							(start -0.1778 -0.2794)
							(mid -0.249642 -0.249642)
							(end -0.2794 -0.1778)
						)
						(arc
							(start -0.2794 0.1778)
							(mid -0.249642 0.249642)
							(end -0.1778 0.2794)
						)
						(arc
							(start 0.1778 0.2794)
							(mid 0.249642 0.249642)
							(end 0.2794 0.1778)
						)
						(arc
							(start 0.2794 -0.1778)
							(mid 0.249642 -0.249642)
							(end 0.1778 -0.2794)
						)
					)
					(width 0)
					(fill yes)
				)
			)
		)
		(pad "2" smd custom
			(at 0 0.4445 90)
			(size 0.1397 0.1397)
			(layers "F.Cu" "F.Mask" "F.Paste")
			(net "AGND_CURRENT_MON")
			(options
				(clearance outline)
				(anchor circle)
			)
			(primitives
				(gr_poly
					(pts
						(arc
							(start -0.1778 -0.2794)
							(mid -0.249642 -0.249642)
							(end -0.2794 -0.1778)
						)
						(arc
							(start -0.2794 0.1778)
							(mid -0.249642 0.249642)
							(end -0.1778 0.2794)
						)
						(arc
							(start 0.1778 0.2794)
							(mid 0.249642 0.249642)
							(end 0.2794 0.1778)
						)
						(arc
							(start 0.2794 -0.1778)
							(mid 0.249642 -0.249642)
							(end 0.1778 -0.2794)
						)
					)
					(width 0)
					(fill yes)
				)
			)
		)
	)
	(footprint ""
		(layer "F.Cu")
		(at 146.4056 -32.913828 -78)
		(property "Reference" "VIA17"
			(at 0 0 282)
			(layer "F.SilkS")
			(hide yes)
			(effects
				(font
					(size 1.27 1.27)
				)
			)
		)
		(property "Value" "100OHM-8L-1D6MM-L13-GP"
			(at 3.289333 0.050849 282)
			(unlocked yes)
			(layer "F.Fab")
			(hide yes)
			(effects
				(font
					(size 1.016 1.016)
					(thickness 0.1524)
				)
			)
		)
		(property "Device Type" "VIA-PCIE-4P-409091"
			(at 3.289207 -1.473208 282)
			(unlocked yes)
			(layer "F.Fab")
			(hide yes)
			(effects
				(font
					(size 1.016 1.016)
					(thickness 0.1524)
				)
			)
		)
		(duplicate_pad_numbers_are_jumpers no)
		(fp_poly
			(pts
				(xy -2.044719 -0.457296) (xy 2.04468 -0.457296) (xy 2.044681 0.457104) (xy -2.044719 0.457104)
			)
			(stroke
				(width 0)
				(type default)
			)
			(fill no)
			(layer "F.CrtYd")
		)
		(fp_poly
			(pts
				(xy -2.044719 -0.457296) (xy 2.04468 -0.457296) (xy 2.044681 0.457104) (xy -2.044719 0.457104)
			)
			(stroke
				(width 0)
				(type default)
			)
			(fill no)
			(layer "F.Fab")
		)
		(pad "1" thru_hole circle
			(at -1.5875 0 282)
			(size 0.508 0.508)
			(drill 0.254)
			(layers "*.Cu" "*.Mask")
			(remove_unused_layers no)
			(net "GND")
			(clearance 0.2032)
			(thermal_gap 0.2032)
		)
		(pad "2" thru_hole circle
			(at -0.5715 0.000001 282)
			(size 0.508 0.508)
			(drill 0.254)
			(layers "*.Cu" "*.Mask")
			(remove_unused_layers no)
			(net "PHY_SCC_TO_IOC_C_40_DP")
			(clearance 0.2032)
			(thermal_gap 0.2032)
		)
		(pad "3" thru_hole circle
			(at 0.5715 -0.000001 282)
			(size 0.508 0.508)
			(drill 0.254)
			(layers "*.Cu" "*.Mask")
			(remove_unused_layers no)
			(net "PHY_SCC_TO_IOC_C_40_DN")
			(clearance 0.2032)
			(thermal_gap 0.2032)
		)
		(pad "4" thru_hole circle
			(at 1.5875 0 282)
			(size 0.508 0.508)
			(drill 0.254)
			(layers "*.Cu" "*.Mask")
			(remove_unused_layers no)
			(net "GND")
			(clearance 0.2032)
			(thermal_gap 0.2032)
		)
	)
	(footprint ""
		(layer "F.Cu")
		(at 12.827 -47.0408 180)
		(property "Reference" "R522"
			(at 0 0 180)
			(layer "F.SilkS")
			(hide yes)
			(effects
				(font
					(size 1.27 1.27)
				)
			)
		)
		(property "Value" "10R2F-L-GP"
			(at 0.064008 -3.993896 180)
			(unlocked yes)
			(layer "F.Fab")
			(hide yes)
			(effects
				(font
					(size 1.016 1.016)
					(thickness 0.1524)
				)
			)
		)
		(property "Device Type" "R402H14"
			(at 0.064008 -5.517896 180)
			(unlocked yes)
			(layer "F.Fab")
			(hide yes)
			(effects
				(font
					(size 1.016 1.016)
					(thickness 0.1524)
				)
			)
		)
		(duplicate_pad_numbers_are_jumpers no)
		(fp_line
			(start 0.508 -0.9398)
			(end -0.508 -0.9398)
			(stroke
				(width 0.1524)
				(type default)
			)
			(layer "F.SilkS")
		)
		(fp_line
			(start -0.508 -0.9398)
			(end -0.508 0.9398)
			(stroke
				(width 0.1524)
				(type default)
			)
			(layer "F.SilkS")
		)
		(fp_rect
			(start -0.508 0.9398)
			(end 0.508 -0.9398)
			(stroke
				(width 0)
				(type default)
			)
			(fill no)
			(layer "F.CrtYd")
		)
		(fp_rect
			(start -0.508 0.9398)
			(end 0.508 -0.9398)
			(stroke
				(width 0)
				(type default)
			)
			(fill no)
			(layer "F.Fab")
		)
		(pad "1" smd custom
			(at 0 -0.4445 180)
			(size 0.1397 0.1397)
			(layers "F.Cu" "F.Mask" "F.Paste")
			(net "MB0_CM_SENSE_R1_P")
			(options
				(clearance outline)
				(anchor circle)
			)
			(primitives
				(gr_poly
					(pts
						(arc
							(start -0.1778 -0.2794)
							(mid -0.249642 -0.249642)
							(end -0.2794 -0.1778)
						)
						(arc
							(start -0.2794 0.1778)
							(mid -0.249642 0.249642)
							(end -0.1778 0.2794)
						)
						(arc
							(start 0.1778 0.2794)
							(mid 0.249642 0.249642)
							(end 0.2794 0.1778)
						)
						(arc
							(start 0.2794 -0.1778)
							(mid 0.249642 -0.249642)
							(end 0.1778 -0.2794)
						)
					)
					(width 0)
					(fill yes)
				)
			)
		)
		(pad "2" smd custom
			(at 0 0.4445 180)
			(size 0.1397 0.1397)
			(layers "F.Cu" "F.Mask" "F.Paste")
			(net "MB0_HS_SENSE_P")
			(options
				(clearance outline)
				(anchor circle)
			)
			(primitives
				(gr_poly
					(pts
						(arc
							(start -0.1778 -0.2794)
							(mid -0.249642 -0.249642)
							(end -0.2794 -0.1778)
						)
						(arc
							(start -0.2794 0.1778)
							(mid -0.249642 0.249642)
							(end -0.1778 0.2794)
						)
						(arc
							(start 0.1778 0.2794)
							(mid 0.249642 0.249642)
							(end 0.2794 0.1778)
						)
						(arc
							(start 0.2794 -0.1778)
							(mid 0.249642 -0.249642)
							(end 0.1778 -0.2794)
						)
					)
					(width 0)
					(fill yes)
				)
			)
		)
	)
	(footprint ""
		(layer "F.Cu")
		(at 83.954874 -104.358694)
		(property "Reference" "R552"
			(at 0 0 0)
			(layer "F.SilkS")
			(hide yes)
			(effects
				(font
					(size 1.27 1.27)
				)
			)
		)
		(property "Value" "0R2J-2-GP"
			(at 0.064008 -3.993896 0)
			(unlocked yes)
			(layer "F.Fab")
			(hide yes)
			(effects
				(font
					(size 1.016 1.016)
					(thickness 0.1524)
				)
			)
		)
		(property "Device Type" "R402H16"
			(at 0.064008 -5.517896 0)
			(unlocked yes)
			(layer "F.Fab")
			(hide yes)
			(effects
				(font
					(size 1.016 1.016)
					(thickness 0.1524)
				)
			)
		)
		(duplicate_pad_numbers_are_jumpers no)
		(fp_line
			(start -0.508 -0.9398)
			(end -0.508 0.9398)
			(stroke
				(width 0.1524)
				(type default)
			)
			(layer "F.SilkS")
		)
		(fp_line
			(start 0.508 -0.9398)
			(end -0.508 -0.9398)
			(stroke
				(width 0.1524)
				(type default)
			)
			(layer "F.SilkS")
		)
		(fp_rect
			(start -0.508 0.9398)
			(end 0.508 -0.9398)
			(stroke
				(width 0)
				(type default)
			)
			(fill no)
			(layer "F.CrtYd")
		)
		(fp_rect
			(start -0.508 0.9398)
			(end 0.508 -0.9398)
			(stroke
				(width 0)
				(type default)
			)
			(fill no)
			(layer "F.Fab")
		)
		(pad "1" smd custom
			(at 0 -0.4445)
			(size 0.1397 0.1397)
			(layers "F.Cu" "F.Mask" "F.Paste")
			(net "SCC_FULL_PWR_EN_U48")
			(options
				(clearance outline)
				(anchor circle)
			)
			(primitives
				(gr_poly
					(pts
						(arc
							(start -0.1778 -0.2794)
							(mid -0.249642 -0.249642)
							(end -0.2794 -0.1778)
						)
						(arc
							(start -0.2794 0.1778)
							(mid -0.249642 0.249642)
							(end -0.1778 0.2794)
						)
						(arc
							(start 0.1778 0.2794)
							(mid 0.249642 0.249642)
							(end 0.2794 0.1778)
						)
						(arc
							(start 0.2794 -0.1778)
							(mid 0.249642 -0.249642)
							(end 0.1778 -0.2794)
						)
					)
					(width 0)
					(fill yes)
				)
			)
		)
		(pad "2" smd custom
			(at 0 0.4445)
			(size 0.1397 0.1397)
			(layers "F.Cu" "F.Mask" "F.Paste")
			(net "SCC_FULL_PWR_EN")
			(options
				(clearance outline)
				(anchor circle)
			)
			(primitives
				(gr_poly
					(pts
						(arc
							(start -0.1778 -0.2794)
							(mid -0.249642 -0.249642)
							(end -0.2794 -0.1778)
						)
						(arc
							(start -0.2794 0.1778)
							(mid -0.249642 0.249642)
							(end -0.1778 0.2794)
						)
						(arc
							(start 0.1778 0.2794)
							(mid 0.249642 0.249642)
							(end 0.2794 0.1778)
						)
						(arc
							(start 0.2794 -0.1778)
							(mid 0.249642 -0.249642)
							(end 0.1778 -0.2794)
						)
					)
					(width 0)
					(fill yes)
				)
			)
		)
	)
	(footprint ""
		(layer "F.Cu")
		(at 70.8406 -83.4136 -90)
		(property "Reference" "C599"
			(at 0 0 270)
			(layer "F.SilkS")
			(hide yes)
			(effects
				(font
					(size 1.27 1.27)
				)
			)
		)
		(property "Value" "SCD1U16V2KX-3GP"
			(at 1.1811 -2.7051 270)
			(unlocked yes)
			(layer "F.Fab")
			(hide yes)
			(effects
				(font
					(size 1.016 1.016)
					(thickness 0.1524)
				)
			)
		)
		(property "Device Type" "C402H22"
			(at 1.1811 -4.2291 270)
			(unlocked yes)
			(layer "F.Fab")
			(hide yes)
			(effects
				(font
					(size 1.016 1.016)
					(thickness 0.1524)
				)
			)
		)
		(duplicate_pad_numbers_are_jumpers no)
		(fp_rect
			(start -0.4318 0.9525)
			(end 0.4318 -0.9525)
			(stroke
				(width 0)
				(type default)
			)
			(fill no)
			(layer "F.CrtYd")
		)
		(fp_rect
			(start -0.4318 0.9525)
			(end 0.4318 -0.9525)
			(stroke
				(width 0)
				(type default)
			)
			(fill no)
			(layer "F.Fab")
		)
		(pad "1" smd custom
			(at 0 -0.4445 270)
			(size 0.1524 0.1524)
			(layers "F.Cu" "F.Mask" "F.Paste")
			(net "P1V8_E")
			(options
				(clearance outline)
				(anchor circle)
			)
			(primitives
				(gr_poly
					(pts
						(arc
							(start 0.3048 -0.2032)
							(mid 0.275042 -0.275042)
							(end 0.2032 -0.3048)
						)
						(arc
							(start -0.2032 -0.3048)
							(mid -0.275042 -0.275042)
							(end -0.3048 -0.2032)
						)
						(arc
							(start -0.3048 0.2032)
							(mid -0.275042 0.275042)
							(end -0.2032 0.3048)
						)
						(arc
							(start 0.2032 0.3048)
							(mid 0.275042 0.275042)
							(end 0.3048 0.2032)
						)
					)
					(width 0)
					(fill yes)
				)
			)
		)
		(pad "2" smd custom
			(at 0 0.4445 270)
			(size 0.1524 0.1524)
			(layers "F.Cu" "F.Mask" "F.Paste")
			(net "GND")
			(options
				(clearance outline)
				(anchor circle)
			)
			(primitives
				(gr_poly
					(pts
						(arc
							(start 0.3048 -0.2032)
							(mid 0.275042 -0.275042)
							(end 0.2032 -0.3048)
						)
						(arc
							(start -0.2032 -0.3048)
							(mid -0.275042 -0.275042)
							(end -0.3048 -0.2032)
						)
						(arc
							(start -0.3048 0.2032)
							(mid -0.275042 0.275042)
							(end -0.2032 0.3048)
						)
						(arc
							(start 0.2032 0.3048)
							(mid 0.275042 0.275042)
							(end 0.3048 0.2032)
						)
					)
					(width 0)
					(fill yes)
				)
			)
		)
	)
)
